#ISCELL
  mstr_misc dns *
  *
#ISCELL
  mstr_symbols design_note *
  *
#ISCELL
  mstr_symbols intel_corp_bpage *
  *
#ISCELL
  mstr_standard offpage *
  page204_i1
#CELL
  mstr_discrete res *
  page204_i103
#CELL
  w_hdl ind-120nh-30-gp *
  page204_i104
#CELL
  w_hdl ind-80nh-1-gp *
  page204_i105
#CELL
  w_hdl sc1u10v2kx-4-gp *
  page204_i113
#CELL
  w_hdl 1r3f-gp *
  page204_i114
#ISCELL
  mstr_symbols gnd *
  page204_i13
#CELL
  mstr_discrete cap *
  page204_i18
#ISCELL
  mstr_standard offpage *
  page204_i2
#CELL
  mstr_discrete cap *
  page204_i22
#ISCELL
  mstr_standard offpage *
  page204_i3
#CELL
  mstr_discrete cap *
  page204_i34
#CELL
  dev_discrete cap_a *
  page204_i35
#CELL
  mstr_discrete cap *
  page204_i36
#CELL
  mstr_discrete cap *
  page204_i37
#CELL
  mstr_discrete cap *
  page204_i38
#ISCELL
  mstr_symbols pvccin_cpu0 *
  page204_i4
#ISCELL
  mstr_standard offpage *
  page204_i40
#ISCELL
  mstr_symbols vcc_core *
  page204_i41
#CELL
  mstr_discrete cap *
  page204_i42
#ISCELL
  mstr_symbols gnd *
  page204_i43
#ISCELL
  mstr_symbols vcc_core *
  page204_i44
#CELL
  mstr_discrete capp *
  page204_i48
#ISCELL
  mstr_symbols gnd *
  page204_i49
#CELL
  mstr_discrete capp *
  page204_i50
#ISCELL
  mstr_standard offpage *
  page204_i56
#ISCELL
  mstr_standard offpage *
  page204_i57
#ISCELL
  mstr_symbols pvccin_cpu0 *
  page204_i58
#ISCELL
  mstr_symbols gnd *
  page204_i59
#CELL
  mstr_discrete res *
  page204_i60
#CELL
  mstr_discrete res *
  page204_i61
#CELL
  mstr_discrete res *
  page204_i62
#CELL
  mstr_discrete res *
  page204_i63
#CELL
  mstr_discrete res *
  page204_i64
#ISCELL
  mstr_standard offpage *
  page204_i65
#ISCELL
  mstr_standard offpage *
  page204_i66
#CELL
  mstr_discrete capp *
  page204_i67
#ISCELL
  mstr_symbols p12v_stby *
  page204_i68
#ISCELL
  mstr_symbols p5v_stby *
  page204_i69
#CELL
  dev_discrete cap_a *
  page204_i70
#CELL
  mstr_discrete ir354xx *
  page204_i71
#ISCELL
  mstr_symbols gnd *
  page204_i8
#CELL
  mstr_discrete res *
  page204_i83
#ISCELL
  mstr_symbols gnd *
  page204_i84
#CELL
  dev_discrete cap_a *
  page204_i85
#ISCELL
  mstr_symbols gnd *
  page204_i86
#CELL
  mstr_discrete cap *
  page204_i88
#ISCELL
  mstr_symbols gnd *
  page204_i89
#CELL
  dev_discrete cap_a *
  page204_i9
#ISCELL
  mstr_symbols gnd *
  page204_i92
#CELL
  mstr_discrete cap *
  page204_i97
#CELL
  mstr_discrete res *
  page204_i99
